(kicad_pcb
	(version 20260206)
	(generator "pcbnew")
	(generator_version "10.0")
	(general
		(thickness 1.6)
		(legacy_teardrops no)
	)
	(paper "A4")
	(title_block
		(title "Bryce Canyon_IOM_IOC_16318-2_OCP.brd")
		(comment 1 "Bryce Canyon / footprints 950-957 of 1605")
	)
	(layers
		(0 "F.Cu" signal "TOP")
		(4 "In1.Cu" signal "L2GND")
		(6 "In2.Cu" signal "L3")
		(8 "In3.Cu" signal "L4VCC")
		(10 "In4.Cu" signal "L5VCC")
		(12 "In5.Cu" signal "L6")
		(14 "In6.Cu" signal "L7GND")
		(2 "B.Cu" signal "BOTTOM")
		(9 "F.Adhes" user "F.Adhesive")
		(11 "B.Adhes" user "B.Adhesive")
		(13 "F.Paste" user "Package Geometry/Pastemask Top")
		(15 "B.Paste" user "Package Geometry/Pastemask Bottom")
		(5 "F.SilkS" user "Ref Des/Silkscreen Top")
		(7 "B.SilkS" user "Ref Des/Silkscreen Bottom")
		(1 "F.Mask" user "Board Geometry/Soldermask Top")
		(3 "B.Mask" user "Board Geometry/Soldermask Bottom")
		(17 "Dwgs.User" user "User.Drawings")
		(19 "Cmts.User" user "User.Comments")
		(21 "Eco1.User" user "User.Eco1")
		(23 "Eco2.User" user "User.Eco2")
		(25 "Edge.Cuts" user "Board Geometry/Outline")
		(27 "Margin" user)
		(31 "F.CrtYd" user "Package Geometry/Place Bound Top")
		(29 "B.CrtYd" user "Package Geometry/Place Bound Bottom")
		(35 "F.Fab" user "Ref Des/Assembly Top")
		(33 "B.Fab" user "Ref Des/Assembly Bottom")
	)
	(footprint ""
		(layer "B.Cu")
		(at 122.3264 -14.9606 -90)
		(property "Reference" "R743"
			(at 0 0 90)
			(layer "B.SilkS")
			(hide yes)
			(effects
				(font
					(size 1.27 1.27)
				)
				(justify mirror)
			)
		)
		(property "Value" "100KR2F-L1-GP"
			(at -0.064008 -3.993896 270)
			(unlocked yes)
			(layer "B.Fab")
			(hide yes)
			(effects
				(font
					(size 1.016 1.016)
					(thickness 0.1524)
				)
				(justify mirror)
			)
		)
		(property "Device Type" "R402H16"
			(at -0.064008 -5.517896 270)
			(unlocked yes)
			(layer "B.Fab")
			(hide yes)
			(effects
				(font
					(size 1.016 1.016)
					(thickness 0.1524)
				)
				(justify mirror)
			)
		)
		(duplicate_pad_numbers_are_jumpers no)
		(fp_line
			(start -0.508 -0.9398)
			(end 0.508 -0.9398)
			(stroke
				(width 0.1524)
				(type default)
			)
			(layer "B.SilkS")
		)
		(fp_line
			(start 0.508 -0.9398)
			(end 0.508 0.9398)
			(stroke
				(width 0.1524)
				(type default)
			)
			(layer "B.SilkS")
		)
		(fp_rect
			(start 0.508 0.9398)
			(end -0.508 -0.9398)
			(stroke
				(width 0)
				(type default)
			)
			(fill no)
			(layer "B.CrtYd")
		)
		(fp_rect
			(start 0.508 0.9398)
			(end -0.508 -0.9398)
			(stroke
				(width 0)
				(type default)
			)
			(fill no)
			(layer "B.Fab")
		)
		(pad "1" smd custom
			(at 0 -0.4445 90)
			(size 0.1397 0.1397)
			(layers "B.Cu" "B.Mask" "B.Paste")
			(net "P12V_IOM")
			(options
				(clearance outline)
				(anchor circle)
			)
			(primitives
				(gr_poly
					(pts
						(arc
							(start -0.1778 0.2794)
							(mid -0.249642 0.249642)
							(end -0.2794 0.1778)
						)
						(arc
							(start -0.2794 -0.1778)
							(mid -0.249642 -0.249642)
							(end -0.1778 -0.2794)
						)
						(arc
							(start 0.1778 -0.2794)
							(mid 0.249642 -0.249642)
							(end 0.2794 -0.1778)
						)
						(arc
							(start 0.2794 0.1778)
							(mid 0.249642 0.249642)
							(end 0.1778 0.2794)
						)
					)
					(width 0)
					(fill yes)
				)
			)
		)
		(pad "2" smd custom
			(at 0 0.4445 90)
			(size 0.1397 0.1397)
			(layers "B.Cu" "B.Mask" "B.Paste")
			(net "IOM_ADM1278_EN")
			(options
				(clearance outline)
				(anchor circle)
			)
			(primitives
				(gr_poly
					(pts
						(arc
							(start -0.1778 0.2794)
							(mid -0.249642 0.249642)
							(end -0.2794 0.1778)
						)
						(arc
							(start -0.2794 -0.1778)
							(mid -0.249642 -0.249642)
							(end -0.1778 -0.2794)
						)
						(arc
							(start 0.1778 -0.2794)
							(mid 0.249642 -0.249642)
							(end 0.2794 -0.1778)
						)
						(arc
							(start 0.2794 0.1778)
							(mid 0.249642 0.249642)
							(end 0.1778 0.2794)
						)
					)
					(width 0)
					(fill yes)
				)
			)
		)
	)
	(footprint ""
		(layer "B.Cu")
		(at 55.0164 -127.24892)
		(property "Reference" "U37"
			(at 0 0 0)
			(layer "B.SilkS")
			(hide yes)
			(effects
				(font
					(size 1.27 1.27)
				)
				(justify mirror)
			)
		)
		(property "Value" "SN74LVC1G08DCKR-GP"
			(at 2.3368 -8.6868 0)
			(unlocked yes)
			(layer "B.Fab")
			(hide yes)
			(effects
				(font
					(size 1.016 1.016)
					(thickness 0.1524)
				)
				(justify mirror)
			)
		)
		(property "Device Type" "SC70-5H44"
			(at 2.3114 -10.414 0)
			(unlocked yes)
			(layer "B.Fab")
			(hide yes)
			(effects
				(font
					(size 1.016 1.016)
					(thickness 0.1524)
				)
				(justify mirror)
			)
		)
		(duplicate_pad_numbers_are_jumpers no)
		(fp_line
			(start -1.3843 -1.8034)
			(end -1.3843 -1.1176)
			(stroke
				(width 0.3302)
				(type default)
			)
			(layer "B.SilkS")
		)
		(fp_line
			(start -1.27 -1.7018)
			(end -1.27 1.7018)
			(stroke
				(width 0.1524)
				(type default)
			)
			(layer "B.SilkS")
		)
		(fp_line
			(start -1.27 1.7018)
			(end 1.27 1.7018)
			(stroke
				(width 0.1524)
				(type default)
			)
			(layer "B.SilkS")
		)
		(fp_line
			(start -0.6604 -1.8034)
			(end -1.3843 -1.8034)
			(stroke
				(width 0.3302)
				(type default)
			)
			(layer "B.SilkS")
		)
		(fp_line
			(start 1.27 -1.7018)
			(end -1.27 -1.7018)
			(stroke
				(width 0.1524)
				(type default)
			)
			(layer "B.SilkS")
		)
		(fp_line
			(start 1.27 1.7018)
			(end 1.27 -1.7018)
			(stroke
				(width 0.1524)
				(type default)
			)
			(layer "B.SilkS")
		)
		(fp_rect
			(start 1.524 1.9558)
			(end -1.524 -1.9558)
			(stroke
				(width 0)
				(type default)
			)
			(fill no)
			(layer "B.CrtYd")
		)
		(fp_poly
			(pts
				(xy 1.524 -1.9558) (xy -1.524 -1.9558) (xy -1.524 1.9558) (xy 1.524 1.9558)
			)
			(stroke
				(width 0)
				(type default)
			)
			(fill no)
			(layer "B.Fab")
		)
		(pad "1" smd rect
			(at -0.65024 -0.8255 180)
			(size 0.4064 1.2192)
			(layers "B.Cu" "B.Mask" "B.Paste")
			(net "RST_BMC_EXTRST_N_1")
		)
		(pad "2" smd rect
			(at 0 -0.8255 180)
			(size 0.4064 1.2192)
			(layers "B.Cu" "B.Mask" "B.Paste")
			(net "DEBUG_RST_BTN_N_R")
		)
		(pad "3" smd rect
			(at 0.65024 -0.8255 180)
			(size 0.4064 1.2192)
			(layers "B.Cu" "B.Mask" "B.Paste")
			(net "GND")
		)
		(pad "4" smd rect
			(at 0.65024 0.8255 180)
			(size 0.4064 1.2192)
			(layers "B.Cu" "B.Mask" "B.Paste")
			(net "RST_BMC_EXTRST_N")
		)
		(pad "5" smd rect
			(at -0.65024 0.8255 180)
			(size 0.4064 1.2192)
			(layers "B.Cu" "B.Mask" "B.Paste")
			(net "P3V3_STBY")
		)
	)
	(footprint ""
		(layer "B.Cu")
		(at 61.0362 -146.0754 90)
		(property "Reference" "R163"
			(at 0 0 90)
			(layer "B.SilkS")
			(hide yes)
			(effects
				(font
					(size 1.27 1.27)
				)
				(justify mirror)
			)
		)
		(property "Value" "0R2J-2-GP"
			(at -0.064008 -3.993896 90)
			(unlocked yes)
			(layer "B.Fab")
			(hide yes)
			(effects
				(font
					(size 1.016 1.016)
					(thickness 0.1524)
				)
				(justify mirror)
			)
		)
		(property "Device Type" "R402H16"
			(at -0.064008 -5.517896 90)
			(unlocked yes)
			(layer "B.Fab")
			(hide yes)
			(effects
				(font
					(size 1.016 1.016)
					(thickness 0.1524)
				)
				(justify mirror)
			)
		)
		(duplicate_pad_numbers_are_jumpers no)
		(fp_line
			(start 0.508 -0.9398)
			(end 0.508 0.9398)
			(stroke
				(width 0.1524)
				(type default)
			)
			(layer "B.SilkS")
		)
		(fp_line
			(start -0.508 -0.9398)
			(end 0.508 -0.9398)
			(stroke
				(width 0.1524)
				(type default)
			)
			(layer "B.SilkS")
		)
		(fp_rect
			(start 0.508 0.9398)
			(end -0.508 -0.9398)
			(stroke
				(width 0)
				(type default)
			)
			(fill no)
			(layer "B.CrtYd")
		)
		(fp_rect
			(start 0.508 0.9398)
			(end -0.508 -0.9398)
			(stroke
				(width 0)
				(type default)
			)
			(fill no)
			(layer "B.Fab")
		)
		(pad "1" smd custom
			(at 0 -0.4445 270)
			(size 0.1397 0.1397)
			(layers "B.Cu" "B.Mask" "B.Paste")
			(net "BMC_SMB13_CLK")
			(options
				(clearance outline)
				(anchor circle)
			)
			(primitives
				(gr_poly
					(pts
						(arc
							(start -0.1778 0.2794)
							(mid -0.249642 0.249642)
							(end -0.2794 0.1778)
						)
						(arc
							(start -0.2794 -0.1778)
							(mid -0.249642 -0.249642)
							(end -0.1778 -0.2794)
						)
						(arc
							(start 0.1778 -0.2794)
							(mid 0.249642 -0.249642)
							(end 0.2794 -0.1778)
						)
						(arc
							(start 0.2794 0.1778)
							(mid 0.249642 0.249642)
							(end 0.1778 0.2794)
						)
					)
					(width 0)
					(fill yes)
				)
			)
		)
		(pad "2" smd custom
			(at 0 0.4445 270)
			(size 0.1397 0.1397)
			(layers "B.Cu" "B.Mask" "B.Paste")
			(net "I2C_MEZZ_FRU_SENSOR_SCL")
			(options
				(clearance outline)
				(anchor circle)
			)
			(primitives
				(gr_poly
					(pts
						(arc
							(start -0.1778 0.2794)
							(mid -0.249642 0.249642)
							(end -0.2794 0.1778)
						)
						(arc
							(start -0.2794 -0.1778)
							(mid -0.249642 -0.249642)
							(end -0.1778 -0.2794)
						)
						(arc
							(start 0.1778 -0.2794)
							(mid 0.249642 -0.249642)
							(end 0.2794 -0.1778)
						)
						(arc
							(start 0.2794 0.1778)
							(mid 0.249642 0.249642)
							(end 0.1778 0.2794)
						)
					)
					(width 0)
					(fill yes)
				)
			)
		)
	)
	(footprint ""
		(layer "B.Cu")
		(at 61.0108 -141.859 90)
		(property "Reference" "R185"
			(at 0 0 90)
			(layer "B.SilkS")
			(hide yes)
			(effects
				(font
					(size 1.27 1.27)
				)
				(justify mirror)
			)
		)
		(property "Value" "2K2R2F-GP"
			(at -0.064008 -3.993896 90)
			(unlocked yes)
			(layer "B.Fab")
			(hide yes)
			(effects
				(font
					(size 1.016 1.016)
					(thickness 0.1524)
				)
				(justify mirror)
			)
		)
		(property "Device Type" "R402H16"
			(at -0.064008 -5.517896 90)
			(unlocked yes)
			(layer "B.Fab")
			(hide yes)
			(effects
				(font
					(size 1.016 1.016)
					(thickness 0.1524)
				)
				(justify mirror)
			)
		)
		(duplicate_pad_numbers_are_jumpers no)
		(fp_line
			(start 0.508 -0.9398)
			(end 0.508 0.9398)
			(stroke
				(width 0.1524)
				(type default)
			)
			(layer "B.SilkS")
		)
		(fp_line
			(start -0.508 -0.9398)
			(end 0.508 -0.9398)
			(stroke
				(width 0.1524)
				(type default)
			)
			(layer "B.SilkS")
		)
		(fp_rect
			(start 0.508 0.9398)
			(end -0.508 -0.9398)
			(stroke
				(width 0)
				(type default)
			)
			(fill no)
			(layer "B.CrtYd")
		)
		(fp_rect
			(start 0.508 0.9398)
			(end -0.508 -0.9398)
			(stroke
				(width 0)
				(type default)
			)
			(fill no)
			(layer "B.Fab")
		)
		(pad "1" smd custom
			(at 0 -0.4445 270)
			(size 0.1397 0.1397)
			(layers "B.Cu" "B.Mask" "B.Paste")
			(net "I2C_M2_2_SCL")
			(options
				(clearance outline)
				(anchor circle)
			)
			(primitives
				(gr_poly
					(pts
						(arc
							(start -0.1778 0.2794)
							(mid -0.249642 0.249642)
							(end -0.2794 0.1778)
						)
						(arc
							(start -0.2794 -0.1778)
							(mid -0.249642 -0.249642)
							(end -0.1778 -0.2794)
						)
						(arc
							(start 0.1778 -0.2794)
							(mid 0.249642 -0.249642)
							(end 0.2794 -0.1778)
						)
						(arc
							(start 0.2794 0.1778)
							(mid 0.249642 0.249642)
							(end 0.1778 0.2794)
						)
					)
					(width 0)
					(fill yes)
				)
			)
		)
		(pad "2" smd custom
			(at 0 0.4445 270)
			(size 0.1397 0.1397)
			(layers "B.Cu" "B.Mask" "B.Paste")
			(net "P3V3_STBY")
			(options
				(clearance outline)
				(anchor circle)
			)
			(primitives
				(gr_poly
					(pts
						(arc
							(start -0.1778 0.2794)
							(mid -0.249642 0.249642)
							(end -0.2794 0.1778)
						)
						(arc
							(start -0.2794 -0.1778)
							(mid -0.249642 -0.249642)
							(end -0.1778 -0.2794)
						)
						(arc
							(start 0.1778 -0.2794)
							(mid 0.249642 -0.249642)
							(end 0.2794 -0.1778)
						)
						(arc
							(start 0.2794 0.1778)
							(mid 0.249642 0.249642)
							(end 0.1778 0.2794)
						)
					)
					(width 0)
					(fill yes)
				)
			)
		)
	)
	(footprint ""
		(layer "B.Cu")
		(at 91.86672 -135.2296 -90)
		(property "Reference" "U101"
			(at 0 0 90)
			(layer "B.SilkS")
			(hide yes)
			(effects
				(font
					(size 1.27 1.27)
				)
				(justify mirror)
			)
		)
		(property "Value" "SNLVC1G126DCKR-GP"
			(at 2.3368 -8.6868 270)
			(unlocked yes)
			(layer "B.Fab")
			(hide yes)
			(effects
				(font
					(size 1.016 1.016)
					(thickness 0.1524)
				)
				(justify mirror)
			)
		)
		(property "Device Type" "SC70-5H44"
			(at 2.3114 -10.414 270)
			(unlocked yes)
			(layer "B.Fab")
			(hide yes)
			(effects
				(font
					(size 1.016 1.016)
					(thickness 0.1524)
				)
				(justify mirror)
			)
		)
		(duplicate_pad_numbers_are_jumpers no)
		(fp_line
			(start -1.27 1.7018)
			(end 1.27 1.7018)
			(stroke
				(width 0.1524)
				(type default)
			)
			(layer "B.SilkS")
		)
		(fp_line
			(start 1.27 1.7018)
			(end 1.27 -1.7018)
			(stroke
				(width 0.1524)
				(type default)
			)
			(layer "B.SilkS")
		)
		(fp_line
			(start -1.27 -1.7018)
			(end -1.27 1.7018)
			(stroke
				(width 0.1524)
				(type default)
			)
			(layer "B.SilkS")
		)
		(fp_line
			(start 1.27 -1.7018)
			(end -1.27 -1.7018)
			(stroke
				(width 0.1524)
				(type default)
			)
			(layer "B.SilkS")
		)
		(fp_line
			(start -1.3843 -1.8034)
			(end -1.3843 -1.1176)
			(stroke
				(width 0.3302)
				(type default)
			)
			(layer "B.SilkS")
		)
		(fp_line
			(start -0.6604 -1.8034)
			(end -1.3843 -1.8034)
			(stroke
				(width 0.3302)
				(type default)
			)
			(layer "B.SilkS")
		)
		(fp_rect
			(start 1.524 1.9558)
			(end -1.524 -1.9558)
			(stroke
				(width 0)
				(type default)
			)
			(fill no)
			(layer "B.CrtYd")
		)
		(fp_poly
			(pts
				(xy 1.524 -1.9558) (xy -1.524 -1.9558) (xy -1.524 1.9558) (xy 1.524 1.9558)
			)
			(stroke
				(width 0)
				(type default)
			)
			(fill no)
			(layer "B.Fab")
		)
		(pad "1" smd rect
			(at -0.65024 -0.8255 90)
			(size 0.4064 1.2192)
			(layers "B.Cu" "B.Mask" "B.Paste")
			(net "DEBUG_CARD_PRSNT")
		)
		(pad "2" smd rect
			(at 0 -0.8255 90)
			(size 0.4064 1.2192)
			(layers "B.Cu" "B.Mask" "B.Paste")
			(net "UART_IOM_RX")
		)
		(pad "3" smd rect
			(at 0.65024 -0.8255 90)
			(size 0.4064 1.2192)
			(layers "B.Cu" "B.Mask" "B.Paste")
			(net "GND")
		)
		(pad "4" smd rect
			(at 0.65024 0.8255 90)
			(size 0.4064 1.2192)
			(layers "B.Cu" "B.Mask" "B.Paste")
			(net "DEBUG_UART_IOM_RX")
		)
		(pad "5" smd rect
			(at -0.65024 0.8255 90)
			(size 0.4064 1.2192)
			(layers "B.Cu" "B.Mask" "B.Paste")
			(net "P3V3_STBY")
		)
	)
	(footprint ""
		(layer "B.Cu")
		(at 10.200132 -138.145774 90)
		(property "Reference" "R246"
			(at 0 0 90)
			(layer "B.SilkS")
			(hide yes)
			(effects
				(font
					(size 1.27 1.27)
				)
				(justify mirror)
			)
		)
		(property "Value" "120R2F-GP"
			(at -0.064008 -3.993896 90)
			(unlocked yes)
			(layer "B.Fab")
			(hide yes)
			(effects
				(font
					(size 1.016 1.016)
					(thickness 0.1524)
				)
				(justify mirror)
			)
		)
		(property "Device Type" "R402H16"
			(at -0.064008 -5.517896 90)
			(unlocked yes)
			(layer "B.Fab")
			(hide yes)
			(effects
				(font
					(size 1.016 1.016)
					(thickness 0.1524)
				)
				(justify mirror)
			)
		)
		(duplicate_pad_numbers_are_jumpers no)
		(fp_line
			(start 0.508 -0.9398)
			(end 0.508 0.9398)
			(stroke
				(width 0.1524)
				(type default)
			)
			(layer "B.SilkS")
		)
		(fp_line
			(start -0.508 -0.9398)
			(end 0.508 -0.9398)
			(stroke
				(width 0.1524)
				(type default)
			)
			(layer "B.SilkS")
		)
		(fp_rect
			(start 0.508 0.9398)
			(end -0.508 -0.9398)
			(stroke
				(width 0)
				(type default)
			)
			(fill no)
			(layer "B.CrtYd")
		)
		(fp_rect
			(start 0.508 0.9398)
			(end -0.508 -0.9398)
			(stroke
				(width 0)
				(type default)
			)
			(fill no)
			(layer "B.Fab")
		)
		(pad "1" smd custom
			(at 0 -0.4445 270)
			(size 0.1397 0.1397)
			(layers "B.Cu" "B.Mask" "B.Paste")
			(net "GND")
			(options
				(clearance outline)
				(anchor circle)
			)
			(primitives
				(gr_poly
					(pts
						(arc
							(start -0.1778 0.2794)
							(mid -0.249642 0.249642)
							(end -0.2794 0.1778)
						)
						(arc
							(start -0.2794 -0.1778)
							(mid -0.249642 -0.249642)
							(end -0.1778 -0.2794)
						)
						(arc
							(start 0.1778 -0.2794)
							(mid 0.249642 -0.249642)
							(end 0.2794 -0.1778)
						)
						(arc
							(start 0.2794 0.1778)
							(mid 0.249642 0.249642)
							(end 0.1778 0.2794)
						)
					)
					(width 0)
					(fill yes)
				)
			)
		)
		(pad "2" smd custom
			(at 0 0.4445 270)
			(size 0.1397 0.1397)
			(layers "B.Cu" "B.Mask" "B.Paste")
			(net "MEMA_6")
			(options
				(clearance outline)
				(anchor circle)
			)
			(primitives
				(gr_poly
					(pts
						(arc
							(start -0.1778 0.2794)
							(mid -0.249642 0.249642)
							(end -0.2794 0.1778)
						)
						(arc
							(start -0.2794 -0.1778)
							(mid -0.249642 -0.249642)
							(end -0.1778 -0.2794)
						)
						(arc
							(start 0.1778 -0.2794)
							(mid 0.249642 -0.249642)
							(end 0.2794 -0.1778)
						)
						(arc
							(start 0.2794 0.1778)
							(mid 0.249642 0.249642)
							(end 0.1778 0.2794)
						)
					)
					(width 0)
					(fill yes)
				)
			)
		)
	)
	(footprint ""
		(layer "B.Cu")
		(at 60.7568 -133.858)
		(property "Reference" "TP192"
			(at 0 0 0)
			(layer "B.SilkS")
			(hide yes)
			(effects
				(font
					(size 1.27 1.27)
				)
				(justify mirror)
			)
		)
		(property "Value" "TPAD28-2-GP"
			(at 0.0127 -1.6637 0)
			(unlocked yes)
			(layer "B.Fab")
			(hide yes)
			(effects
				(font
					(size 1.016 1.016)
					(thickness 0.1524)
				)
				(justify mirror)
			)
		)
		(property "Device Type" "TPAD28"
			(at 0.0127 -3.1877 0)
			(unlocked yes)
			(layer "B.Fab")
			(hide yes)
			(effects
				(font
					(size 1.016 1.016)
					(thickness 0.1524)
				)
				(justify mirror)
			)
		)
		(duplicate_pad_numbers_are_jumpers no)
		(fp_poly
			(pts
				(arc
					(start 0.3556 0)
					(mid -0.3556 0)
					(end 0.3556 0)
				)
			)
			(stroke
				(width 0)
				(type default)
			)
			(fill no)
			(layer "B.CrtYd")
		)
		(fp_poly
			(pts
				(arc
					(start 0.6096 0)
					(mid -0.6096 0)
					(end 0.6096 0)
				)
			)
			(stroke
				(width 0)
				(type default)
			)
			(fill no)
			(layer "B.Fab")
		)
		(pad "1" smd circle
			(at 0 0 180)
			(size 0.7112 0.7112)
			(layers "B.Cu" "B.Mask" "B.Paste")
			(net "TP_BMC_EXT1_LED_B")
		)
	)
	(footprint ""
		(layer "B.Cu")
		(at 190.0174 -71.4502)
		(property "Reference" "TP159"
			(at 0 0 0)
			(layer "B.SilkS")
			(hide yes)
			(effects
				(font
					(size 1.27 1.27)
				)
				(justify mirror)
			)
		)
		(property "Value" "TPAD28-2-GP"
			(at 0.0127 -1.6637 0)
			(unlocked yes)
			(layer "B.Fab")
			(hide yes)
			(effects
				(font
					(size 1.016 1.016)
					(thickness 0.1524)
				)
				(justify mirror)
			)
		)
		(property "Device Type" "TPAD28"
			(at 0.0127 -3.1877 0)
			(unlocked yes)
			(layer "B.Fab")
			(hide yes)
			(effects
				(font
					(size 1.016 1.016)
					(thickness 0.1524)
				)
				(justify mirror)
			)
		)
		(duplicate_pad_numbers_are_jumpers no)
		(fp_poly
			(pts
				(arc
					(start 0.3556 0)
					(mid -0.3556 0)
					(end 0.3556 0)
				)
			)
			(stroke
				(width 0)
				(type default)
			)
			(fill no)
			(layer "B.CrtYd")
		)
		(fp_poly
			(pts
				(arc
					(start 0.6096 0)
					(mid -0.6096 0)
					(end 0.6096 0)
				)
			)
			(stroke
				(width 0)
				(type default)
			)
			(fill no)
			(layer "B.Fab")
		)
		(pad "1" smd circle
			(at 0 0 180)
			(size 0.7112 0.7112)
			(layers "B.Cu" "B.Mask" "B.Paste")
			(net "SPARE3")
		)
	)
)
